# T6G (Grand Teton) — schematic netlist excerpt (pin names and nets, part order shuffled) for the footprints in the layout excerpt that follows; sources: Cadence DE-HDL packaged netlist, KiCad conversion of 04192023_DAF0TMB3IC0_F0TG_MB_C_brd_V02_OCP.brd

J7  SCONN8_G802M0083150RD3HR  IO  pkg HEADER2X4SXN  page 54
  \1\  = CPU1_XTRIG_R1_L4
  \2\  = GND
  \3\  = CPU1_XTRIG_R1_L5
  \4\  = GND
  \5\  = CPU1_XTRIG_R1_L6
  \6\  = GND
  \7\  = CPU1_XTRIG_R1_L7
  \8\  = GND

C6649  Q_CAP_DIFFBUS  DIFF BUS_0.22UF 6.3V 20% X6S  pkg C0201  page 319 : \1\ = P5E_CPU1_P0_TX_BUF_C_DP<10> ; \2\ = P5E_CPU1_P0_TX_BUF_DP<10>

(kicad_pcb
	(version 20260206)
	(generator "pcbnew")
	(generator_version "10.0")
	(general
		(thickness 1.6)
		(legacy_teardrops no)
	)
	(paper "A4")
	(title_block
		(title "04192023_DAF0TMB3IC0_F0TG_MB_C_brd_V02_OCP.brd")
		(comment 1 "Grand Teton / footprints 130-131 of 8354")
	)
	(layers
		(0 "F.Cu" signal "TOP")
		(4 "In1.Cu" signal "GND")
		(6 "In2.Cu" signal "IN1")
		(8 "In3.Cu" signal "GND1")
		(10 "In4.Cu" signal "IN2")
		(12 "In5.Cu" signal "GND2")
		(14 "In6.Cu" signal "IN3")
		(16 "In7.Cu" signal "GND3")
		(18 "In8.Cu" signal "VCC")
		(20 "In9.Cu" signal "VCC1")
		(22 "In10.Cu" signal "GND4")
		(24 "In11.Cu" signal "IN4")
		(26 "In12.Cu" signal "GND5")
		(28 "In13.Cu" signal "IN5")
		(30 "In14.Cu" signal "GND6")
		(32 "In15.Cu" signal "IN6")
		(34 "In16.Cu" signal "GND7")
		(2 "B.Cu" signal "BOTTOM")
		(9 "F.Adhes" user "F.Adhesive")
		(11 "B.Adhes" user "B.Adhesive")
		(13 "F.Paste" user "Package Geometry/Pastemask Top")
		(15 "B.Paste" user "Package Geometry/Pastemask Bottom")
		(5 "F.SilkS" user "Ref Des/Silkscreen Top")
		(7 "B.SilkS" user "Ref Des/Silkscreen Bottom")
		(1 "F.Mask" user "Board Geometry/Soldermask Top")
		(3 "B.Mask" user "Board Geometry/Soldermask Bottom")
		(17 "Dwgs.User" user "User.Drawings")
		(19 "Cmts.User" user "User.Comments")
		(21 "Eco1.User" user "User.Eco1")
		(23 "Eco2.User" user "User.Eco2")
		(25 "Edge.Cuts" user "Board Geometry/Outline")
		(27 "Margin" user)
		(31 "F.CrtYd" user "Package Geometry/Place Bound Top")
		(29 "B.CrtYd" user "Package Geometry/Place Bound Bottom")
		(35 "F.Fab" user "Ref Des/Assembly Top")
		(33 "B.Fab" user "Ref Des/Assembly Bottom")
	)
	(footprint ""
		(layer "F.Cu")
		(at 7.899908 -51.999896)
		(property "Reference" "J7"
			(at -1.016 -3.495548 0)
			(unlocked yes)
			(layer "F.SilkS")
			(effects
				(font
					(size 0.7874 0.5842)
					(thickness 0.1524)
				)
			)
		)
		(property "Value" ""
			(at 0 0 0)
			(layer "F.Fab")
			(effects
				(font
					(size 1.27 1.27)
				)
			)
		)
		(duplicate_pad_numbers_are_jumpers no)
		(fp_line
			(start -1.700022 -2.739898)
			(end 1.700022 -2.739898)
			(stroke
				(width 0.1524)
				(type default)
			)
			(layer "F.SilkS")
		)
		(fp_line
			(start -1.700022 -2.4257)
			(end -1.700022 -2.739898)
			(stroke
				(width 0.1524)
				(type default)
			)
			(layer "F.SilkS")
		)
		(fp_line
			(start -1.700022 -1.1557)
			(end -1.700022 -1.3843)
			(stroke
				(width 0.1524)
				(type default)
			)
			(layer "F.SilkS")
		)
		(fp_line
			(start -1.700022 0.1143)
			(end -1.700022 -0.1143)
			(stroke
				(width 0.1524)
				(type default)
			)
			(layer "F.SilkS")
		)
		(fp_line
			(start -1.700022 1.3843)
			(end -1.700022 1.1557)
			(stroke
				(width 0.1524)
				(type default)
			)
			(layer "F.SilkS")
		)
		(fp_line
			(start -1.700022 2.739898)
			(end -1.700022 2.4257)
			(stroke
				(width 0.1524)
				(type default)
			)
			(layer "F.SilkS")
		)
		(fp_line
			(start 1.700022 -2.739898)
			(end 1.700022 -2.4257)
			(stroke
				(width 0.1524)
				(type default)
			)
			(layer "F.SilkS")
		)
		(fp_line
			(start 1.700022 -1.3843)
			(end 1.700022 -1.1557)
			(stroke
				(width 0.1524)
				(type default)
			)
			(layer "F.SilkS")
		)
		(fp_line
			(start 1.700022 -0.1143)
			(end 1.700022 0.1143)
			(stroke
				(width 0.1524)
				(type default)
			)
			(layer "F.SilkS")
		)
		(fp_line
			(start 1.700022 1.1557)
			(end 1.700022 1.3843)
			(stroke
				(width 0.1524)
				(type default)
			)
			(layer "F.SilkS")
		)
		(fp_line
			(start 1.700022 2.4257)
			(end 1.700022 2.739898)
			(stroke
				(width 0.1524)
				(type default)
			)
			(layer "F.SilkS")
		)
		(fp_line
			(start 1.700022 2.739898)
			(end -1.700022 2.739898)
			(stroke
				(width 0.1524)
				(type default)
			)
			(layer "F.SilkS")
		)
		(fp_poly
			(pts
				(xy -3.383534 -1.905) (xy -4.399534 -1.397) (xy -4.399534 -2.413)
			)
			(stroke
				(width 0)
				(type default)
			)
			(fill yes)
			(layer "F.SilkS")
		)
		(fp_line
			(start -1.700022 -2.739898)
			(end 1.700022 -2.739898)
			(stroke
				(width 0.1)
				(type default)
			)
			(layer "F.Fab")
		)
		(fp_line
			(start -1.700022 2.739898)
			(end -1.700022 -2.739898)
			(stroke
				(width 0.1)
				(type default)
			)
			(layer "F.Fab")
		)
		(fp_line
			(start 1.700022 -2.739898)
			(end 1.700022 2.739898)
			(stroke
				(width 0.1)
				(type default)
			)
			(layer "F.Fab")
		)
		(fp_line
			(start 1.700022 2.739898)
			(end -1.700022 2.739898)
			(stroke
				(width 0.1)
				(type default)
			)
			(layer "F.Fab")
		)
		(fp_poly
			(pts
				(xy -4.399534 -2.413) (xy -4.399534 -1.397) (xy -3.383534 -1.905)
			)
			(stroke
				(width 0)
				(type default)
			)
			(fill yes)
			(layer "F.Fab")
		)
		(pad "1" smd rect
			(at -2.050034 -1.905 270)
			(size 0.762 2.413)
			(layers "F.Cu" "F.Mask" "F.Paste")
			(net "CPU1_XTRIG_R1_L4")
		)
		(pad "2" smd rect
			(at 2.050034 -1.905 270)
			(size 0.762 2.413)
			(layers "F.Cu" "F.Mask" "F.Paste")
			(net "GND")
		)
		(pad "3" smd rect
			(at -2.050034 -0.635 270)
			(size 0.762 2.413)
			(layers "F.Cu" "F.Mask" "F.Paste")
			(net "CPU1_XTRIG_R1_L5")
		)
		(pad "4" smd rect
			(at 2.050034 -0.635 270)
			(size 0.762 2.413)
			(layers "F.Cu" "F.Mask" "F.Paste")
			(net "GND")
		)
		(pad "5" smd rect
			(at -2.050034 0.635 270)
			(size 0.762 2.413)
			(layers "F.Cu" "F.Mask" "F.Paste")
			(net "CPU1_XTRIG_R1_L6")
		)
		(pad "6" smd rect
			(at 2.050034 0.635 270)
			(size 0.762 2.413)
			(layers "F.Cu" "F.Mask" "F.Paste")
			(net "GND")
		)
		(pad "7" smd rect
			(at -2.050034 1.905 270)
			(size 0.762 2.413)
			(layers "F.Cu" "F.Mask" "F.Paste")
			(net "CPU1_XTRIG_R1_L7")
		)
		(pad "8" smd rect
			(at 2.050034 1.905 270)
			(size 0.762 2.413)
			(layers "F.Cu" "F.Mask" "F.Paste")
			(net "GND")
		)
	)
	(footprint ""
		(layer "F.Cu")
		(at 79.315564 -408.517344 -90)
		(property "Reference" "C6649"
			(at 0 0 270)
			(layer "F.SilkS")
			(hide yes)
			(effects
				(font
					(size 1.27 1.27)
				)
			)
		)
		(property "Value" ""
			(at 0 0 270)
			(layer "F.Fab")
			(effects
				(font
					(size 1.27 1.27)
				)
			)
		)
		(duplicate_pad_numbers_are_jumpers no)
		(fp_line
			(start -0.299974 0.150114)
			(end -0.299974 -0.150114)
			(stroke
				(width 0.1)
				(type default)
			)
			(layer "F.Fab")
		)
		(fp_line
			(start 0.299974 0.150114)
			(end -0.299974 0.150114)
			(stroke
				(width 0.1)
				(type default)
			)
			(layer "F.Fab")
		)
		(fp_line
			(start -0.299974 -0.150114)
			(end 0.299974 -0.150114)
			(stroke
				(width 0.1)
				(type default)
			)
			(layer "F.Fab")
		)
		(fp_line
			(start 0.299974 -0.150114)
			(end 0.299974 0.150114)
			(stroke
				(width 0.1)
				(type default)
			)
			(layer "F.Fab")
		)
		(pad "1" smd rect
			(at -0.2667 0 270)
			(size 0.3048 0.381)
			(layers "F.Cu" "F.Mask" "F.Paste")
			(net "P5E_CPU1_P0_TX_BUF_C_DP<10>")
		)
		(pad "2" smd rect
			(at 0.2667 0 270)
			(size 0.3048 0.381)
			(layers "F.Cu" "F.Mask" "F.Paste")
			(net "P5E_CPU1_P0_TX_BUF_DP<10>")
		)
	)
)
